# BASEBOARD_FAB2 (Tioga Pass) — schematic netlist excerpt (pin names and nets, part order shuffled) for the footprints in the layout excerpt that follows; sources: Cadence DE-HDL packaged netlist, KiCad conversion of Wiwynn_Tioga_Pass_MB.brd

R4B4  RES  6.19K 1% CHIP  pkg 0402  page 234 : A = VR_FB_PVPP_KLM ; B = AGND_PVPP_KLM

T1P11  TPAD-DIFF-4P-GP  pkg DISCRET-GB3  page 256
  \1\  = L12_73OHM_6INCH_DP
  \2\  = L12_73OHM_6INCH_DN
  GND1  = GND
  GND2  = GND

(kicad_pcb
	(version 20260206)
	(generator "pcbnew")
	(generator_version "10.0")
	(general
		(thickness 1.6)
		(legacy_teardrops no)
	)
	(paper "A4")
	(title_block
		(title "Wiwynn_Tioga_Pass_MB.brd")
		(comment 1 "Tioga Pass / footprints 737-738 of 4770")
	)
	(layers
		(0 "F.Cu" signal "TOP")
		(4 "In1.Cu" signal "L2GND")
		(6 "In2.Cu" signal "L3")
		(8 "In3.Cu" signal "L4GND")
		(10 "In4.Cu" signal "L5")
		(12 "In5.Cu" signal "L6GND")
		(14 "In6.Cu" signal "L7VCC")
		(16 "In7.Cu" signal "L8VCC")
		(18 "In8.Cu" signal "L9GND")
		(20 "In9.Cu" signal "L10")
		(22 "In10.Cu" signal "L11GND")
		(24 "In11.Cu" signal "L12")
		(26 "In12.Cu" signal "L13GND")
		(2 "B.Cu" signal "BOTTOM")
		(9 "F.Adhes" user "F.Adhesive")
		(11 "B.Adhes" user "B.Adhesive")
		(13 "F.Paste" user "Package Geometry/Pastemask Top")
		(15 "B.Paste" user "Package Geometry/Pastemask Bottom")
		(5 "F.SilkS" user "Ref Des/Silkscreen Top")
		(7 "B.SilkS" user "Ref Des/Silkscreen Bottom")
		(1 "F.Mask" user "Board Geometry/Soldermask Top")
		(3 "B.Mask" user "Board Geometry/Soldermask Bottom")
		(17 "Dwgs.User" user "User.Drawings")
		(19 "Cmts.User" user "User.Comments")
		(21 "Eco1.User" user "User.Eco1")
		(23 "Eco2.User" user "User.Eco2")
		(25 "Edge.Cuts" user "Board Geometry/Outline")
		(27 "Margin" user)
		(31 "F.CrtYd" user "Package Geometry/Place Bound Top")
		(29 "B.CrtYd" user "Package Geometry/Place Bound Bottom")
		(35 "F.Fab" user "Ref Des/Assembly Top")
		(33 "B.Fab" user "Ref Des/Assembly Bottom")
	)
	(footprint ""
		(layer "F.Cu")
		(at 137.730484 12.014454 -90)
		(property "Reference" "T1P11"
			(at 0 0 270)
			(layer "F.SilkS")
			(hide yes)
			(effects
				(font
					(size 1.27 1.27)
				)
			)
		)
		(property "Value" "*"
			(at -3.302 1.12395 270)
			(unlocked yes)
			(layer "F.Fab")
			(hide yes)
			(effects
				(font
					(size 0.889 0.889)
					(thickness 0.1524)
				)
			)
		)
		(property "Device Type" "TPAD-DIFF-4P-GP_DISCRET-GB3-TPA"
			(at -3.302 -0.40005 270)
			(unlocked yes)
			(layer "F.Fab")
			(hide yes)
			(effects
				(font
					(size 0.889 0.889)
					(thickness 0.1524)
				)
			)
		)
		(duplicate_pad_numbers_are_jumpers no)
		(fp_line
			(start -2.286 2.286)
			(end 2.286 2.286)
			(stroke
				(width 0.1524)
				(type default)
			)
			(layer "F.SilkS")
		)
		(fp_line
			(start 2.286 2.286)
			(end 2.286 -2.286)
			(stroke
				(width 0.1524)
				(type default)
			)
			(layer "F.SilkS")
		)
		(fp_line
			(start -2.286 -2.286)
			(end -2.286 2.286)
			(stroke
				(width 0.1524)
				(type default)
			)
			(layer "F.SilkS")
		)
		(fp_line
			(start 2.286 -2.286)
			(end -2.286 -2.286)
			(stroke
				(width 0.1524)
				(type default)
			)
			(layer "F.SilkS")
		)
		(fp_line
			(start -2.413 -2.413)
			(end -2.413 -1.143)
			(stroke
				(width 0.4064)
				(type default)
			)
			(layer "F.SilkS")
		)
		(fp_line
			(start -1.143 -2.413)
			(end -2.413 -2.413)
			(stroke
				(width 0.4064)
				(type default)
			)
			(layer "F.SilkS")
		)
		(fp_rect
			(start -2.54 2.54)
			(end 2.54 -2.54)
			(stroke
				(width 0)
				(type default)
			)
			(fill no)
			(layer "F.CrtYd")
		)
		(fp_rect
			(start -2.54 2.54)
			(end 2.54 -2.54)
			(stroke
				(width 0)
				(type default)
			)
			(fill no)
			(layer "F.Fab")
		)
		(pad "1" thru_hole circle
			(at -1.27 -1.27 270)
			(size 1.524 1.524)
			(drill 0.9144)
			(layers "*.Cu" "*.Mask")
			(remove_unused_layers no)
			(net "L12_73OHM_6INCH_DP")
			(clearance -0.0508)
			(thermal_gap 0.127)
			(padstack
				(mode front_inner_back)
				(layer "Inner"
					(shape circle)
					(size 1.1684 1.1684)
					(clearance 0.127)
				)
				(layer "B.Cu"
					(shape circle)
					(size 1.524 1.524)
					(clearance -0.0508)
				)
			)
		)
		(pad "2" thru_hole circle
			(at 1.27 -1.27 270)
			(size 1.524 1.524)
			(drill 0.9144)
			(layers "*.Cu" "*.Mask")
			(remove_unused_layers no)
			(net "L12_73OHM_6INCH_DN")
			(clearance -0.0508)
			(thermal_gap 0.127)
			(padstack
				(mode front_inner_back)
				(layer "Inner"
					(shape circle)
					(size 1.1684 1.1684)
					(clearance 0.127)
				)
				(layer "B.Cu"
					(shape circle)
					(size 1.524 1.524)
					(clearance -0.0508)
				)
			)
		)
		(pad "GND1" thru_hole rect
			(at -1.27 1.27 270)
			(size 1.524 1.524)
			(drill 0.9144)
			(layers "*.Cu" "*.Mask")
			(remove_unused_layers no)
			(net "GND")
			(clearance -0.0508)
			(thermal_gap 0.127)
			(padstack
				(mode front_inner_back)
				(layer "Inner"
					(shape circle)
					(size 1.1684 1.1684)
					(clearance 0.127)
				)
				(layer "B.Cu"
					(shape rect)
					(size 1.524 1.524)
					(clearance -0.0508)
				)
			)
		)
		(pad "GND2" thru_hole rect
			(at 1.27 1.27 270)
			(size 1.524 1.524)
			(drill 0.9144)
			(layers "*.Cu" "*.Mask")
			(remove_unused_layers no)
			(net "GND")
			(clearance -0.0508)
			(thermal_gap 0.127)
			(padstack
				(mode front_inner_back)
				(layer "Inner"
					(shape circle)
					(size 1.1684 1.1684)
					(clearance 0.127)
				)
				(layer "B.Cu"
					(shape rect)
					(size 1.524 1.524)
					(clearance -0.0508)
				)
			)
		)
	)
	(footprint ""
		(layer "F.Cu")
		(at 174.244 -131.5085)
		(property "Reference" "R4B4"
			(at 0 0 0)
			(layer "F.SilkS")
			(hide yes)
			(effects
				(font
					(size 1.27 1.27)
				)
			)
		)
		(property "Value" ""
			(at 0 0 0)
			(layer "F.Fab")
			(effects
				(font
					(size 1.27 1.27)
				)
			)
		)
		(duplicate_pad_numbers_are_jumpers no)
		(fp_poly
			(pts
				(xy -0.2794 -0.1016) (xy 0.2794 -0.1016) (xy 0.2794 0.9906) (xy -0.2794 0.9906)
			)
			(stroke
				(width 0)
				(type default)
			)
			(fill no)
			(layer "F.CrtYd")
		)
		(fp_line
			(start -0.2794 -0.1016)
			(end -0.2794 0.9906)
			(stroke
				(width 0.1)
				(type default)
			)
			(layer "F.Fab")
		)
		(fp_line
			(start -0.2794 0.9906)
			(end 0.2794 0.9906)
			(stroke
				(width 0.1)
				(type default)
			)
			(layer "F.Fab")
		)
		(fp_line
			(start 0.2794 -0.1016)
			(end -0.2794 -0.1016)
			(stroke
				(width 0.1)
				(type default)
			)
			(layer "F.Fab")
		)
		(fp_line
			(start 0.2794 0.9906)
			(end 0.2794 -0.1016)
			(stroke
				(width 0.1)
				(type default)
			)
			(layer "F.Fab")
		)
		(pad "1" smd rect
			(at 0 0)
			(size 0.508 0.508)
			(layers "F.Cu" "F.Mask" "F.Paste")
			(net "VR_FB_PVPP_KLM")
		)
		(pad "2" smd rect
			(at 0 0.889)
			(size 0.508 0.508)
			(layers "F.Cu" "F.Mask" "F.Paste")
			(net "AGND_PVPP_KLM")
		)
		(zone
			(layer "F.Cu")
			(hatch none 0.5)
			(connect_pads
				(clearance 0)
			)
			(min_thickness 0.25)
			(keepout
				(tracks allowed)
				(vias not_allowed)
				(pads allowed)
				(copperpour not_allowed)
				(footprints allowed)
			)
			(placement
				(enabled no)
				(sheetname "")
			)
			(fill
				(thermal_gap 0.5)
				(thermal_bridge_width 0.5)
				(island_removal_mode 0)
			)
			(polygon
				(pts
					(xy 173.99 -131.2545) (xy 174.498 -131.2545) (xy 174.498 -130.8735) (xy 173.99 -130.8735)
				)
			)
		)
		(zone
			(layer "F.Cu")
			(hatch none 0.5)
			(connect_pads
				(clearance 0)
			)
			(min_thickness 0.25)
			(keepout
				(tracks not_allowed)
				(vias allowed)
				(pads allowed)
				(copperpour not_allowed)
				(footprints allowed)
			)
			(placement
				(enabled no)
				(sheetname "")
			)
			(fill
				(thermal_gap 0.5)
				(thermal_bridge_width 0.5)
				(island_removal_mode 0)
			)
			(polygon
				(pts
					(xy 173.99 -130.8735) (xy 174.498 -130.8735) (xy 174.498 -131.2545) (xy 173.99 -131.2545)
				)
			)
		)
	)
)
